(kicad_pcb
	(version 20260206)
	(generator "pcbnew")
	(generator_version "10.0")
	(general
		(thickness 1.6)
		(legacy_teardrops no)
	)
	(paper "A4")
	(title_block
		(title "04192023_DAF0TMB3IC0_F0TG_MB_C_brd_V02_OCP.brd")
		(comment 1 "Grand Teton / footprints 4459-4465 of 8354")
	)
	(layers
		(0 "F.Cu" signal "TOP")
		(4 "In1.Cu" signal "GND")
		(6 "In2.Cu" signal "IN1")
		(8 "In3.Cu" signal "GND1")
		(10 "In4.Cu" signal "IN2")
		(12 "In5.Cu" signal "GND2")
		(14 "In6.Cu" signal "IN3")
		(16 "In7.Cu" signal "GND3")
		(18 "In8.Cu" signal "VCC")
		(20 "In9.Cu" signal "VCC1")
		(22 "In10.Cu" signal "GND4")
		(24 "In11.Cu" signal "IN4")
		(26 "In12.Cu" signal "GND5")
		(28 "In13.Cu" signal "IN5")
		(30 "In14.Cu" signal "GND6")
		(32 "In15.Cu" signal "IN6")
		(34 "In16.Cu" signal "GND7")
		(2 "B.Cu" signal "BOTTOM")
		(9 "F.Adhes" user "F.Adhesive")
		(11 "B.Adhes" user "B.Adhesive")
		(13 "F.Paste" user "Package Geometry/Pastemask Top")
		(15 "B.Paste" user "Package Geometry/Pastemask Bottom")
		(5 "F.SilkS" user "Ref Des/Silkscreen Top")
		(7 "B.SilkS" user "Ref Des/Silkscreen Bottom")
		(1 "F.Mask" user "Board Geometry/Soldermask Top")
		(3 "B.Mask" user "Board Geometry/Soldermask Bottom")
		(17 "Dwgs.User" user "User.Drawings")
		(19 "Cmts.User" user "User.Comments")
		(21 "Eco1.User" user "User.Eco1")
		(23 "Eco2.User" user "User.Eco2")
		(25 "Edge.Cuts" user "Board Geometry/Outline")
		(27 "Margin" user)
		(31 "F.CrtYd" user "Package Geometry/Place Bound Top")
		(29 "B.CrtYd" user "Package Geometry/Place Bound Bottom")
		(35 "F.Fab" user "Ref Des/Assembly Top")
		(33 "B.Fab" user "Ref Des/Assembly Bottom")
	)
	(footprint ""
		(layer "F.Cu")
		(at 23.916132 -332.638654 90)
		(property "Reference" "PC451"
			(at 0 0 90)
			(layer "F.SilkS")
			(hide yes)
			(effects
				(font
					(size 1.27 1.27)
				)
			)
		)
		(property "Value" ""
			(at 0 0 90)
			(layer "F.Fab")
			(effects
				(font
					(size 1.27 1.27)
				)
			)
		)
		(duplicate_pad_numbers_are_jumpers no)
		(fp_line
			(start 0.7874 -0.4064)
			(end 0.7874 0.4064)
			(stroke
				(width 0.1524)
				(type default)
			)
			(layer "F.SilkS")
		)
		(fp_line
			(start -0.7874 -0.4064)
			(end 0.7874 -0.4064)
			(stroke
				(width 0.1524)
				(type default)
			)
			(layer "F.SilkS")
		)
		(fp_line
			(start 0.7874 0.4064)
			(end -0.7874 0.4064)
			(stroke
				(width 0.1524)
				(type default)
			)
			(layer "F.SilkS")
		)
		(fp_line
			(start -0.7874 0.4064)
			(end -0.7874 -0.4064)
			(stroke
				(width 0.1524)
				(type default)
			)
			(layer "F.SilkS")
		)
		(fp_line
			(start -0.12065 -0.305054)
			(end -0.12065 -0.2794)
			(stroke
				(width 0.1)
				(type default)
			)
			(layer "F.Fab")
		)
		(fp_line
			(start -0.67945 -0.305054)
			(end -0.12065 -0.305054)
			(stroke
				(width 0.1)
				(type default)
			)
			(layer "F.Fab")
		)
		(fp_line
			(start 0.67945 -0.3048)
			(end 0.67945 0.3048)
			(stroke
				(width 0.1)
				(type default)
			)
			(layer "F.Fab")
		)
		(fp_line
			(start 0.12065 -0.3048)
			(end 0.67945 -0.3048)
			(stroke
				(width 0.1)
				(type default)
			)
			(layer "F.Fab")
		)
		(fp_line
			(start 0.12065 -0.2794)
			(end 0.12065 -0.3048)
			(stroke
				(width 0.1)
				(type default)
			)
			(layer "F.Fab")
		)
		(fp_line
			(start -0.12065 -0.2794)
			(end 0.12065 -0.2794)
			(stroke
				(width 0.1)
				(type default)
			)
			(layer "F.Fab")
		)
		(fp_line
			(start 0.120396 0.2794)
			(end -0.12065 0.2794)
			(stroke
				(width 0.1)
				(type default)
			)
			(layer "F.Fab")
		)
		(fp_line
			(start -0.12065 0.2794)
			(end -0.12065 0.3048)
			(stroke
				(width 0.1)
				(type default)
			)
			(layer "F.Fab")
		)
		(fp_line
			(start 0.67945 0.3048)
			(end 0.120396 0.3048)
			(stroke
				(width 0.1)
				(type default)
			)
			(layer "F.Fab")
		)
		(fp_line
			(start 0.120396 0.3048)
			(end 0.120396 0.2794)
			(stroke
				(width 0.1)
				(type default)
			)
			(layer "F.Fab")
		)
		(fp_line
			(start -0.12065 0.3048)
			(end -0.67945 0.3048)
			(stroke
				(width 0.1)
				(type default)
			)
			(layer "F.Fab")
		)
		(fp_line
			(start -0.67945 0.3048)
			(end -0.67945 -0.305054)
			(stroke
				(width 0.1)
				(type default)
			)
			(layer "F.Fab")
		)
		(pad "1" smd circle
			(at -0.40005 0 90)
			(size 0 0)
			(layers "F.Cu" "F.Mask" "F.Paste")
			(net "PVDDIO_P1")
		)
		(pad "2" smd circle
			(at 0.40005 0 90)
			(size 0 0)
			(layers "F.Cu" "F.Mask" "F.Paste")
			(net "GND")
		)
	)
	(footprint ""
		(layer "F.Cu")
		(at 37.402262 -429.790098 -90)
		(property "Reference" "R3286"
			(at 0 0 270)
			(layer "F.SilkS")
			(hide yes)
			(effects
				(font
					(size 1.27 1.27)
				)
			)
		)
		(property "Value" ""
			(at 0 0 270)
			(layer "F.Fab")
			(effects
				(font
					(size 1.27 1.27)
				)
			)
		)
		(duplicate_pad_numbers_are_jumpers no)
		(fp_line
			(start -0.7874 0.4064)
			(end -0.7874 -0.4064)
			(stroke
				(width 0.1524)
				(type default)
			)
			(layer "F.SilkS")
		)
		(fp_line
			(start 0.7874 0.4064)
			(end -0.7874 0.4064)
			(stroke
				(width 0.1524)
				(type default)
			)
			(layer "F.SilkS")
		)
		(fp_line
			(start -0.7874 -0.4064)
			(end 0.7874 -0.4064)
			(stroke
				(width 0.1524)
				(type default)
			)
			(layer "F.SilkS")
		)
		(fp_line
			(start 0.7874 -0.4064)
			(end 0.7874 0.4064)
			(stroke
				(width 0.1524)
				(type default)
			)
			(layer "F.SilkS")
		)
		(fp_line
			(start -0.67945 0.3048)
			(end -0.67945 -0.305054)
			(stroke
				(width 0.1)
				(type default)
			)
			(layer "F.Fab")
		)
		(fp_line
			(start -0.12065 0.3048)
			(end -0.67945 0.3048)
			(stroke
				(width 0.1)
				(type default)
			)
			(layer "F.Fab")
		)
		(fp_line
			(start 0.120396 0.3048)
			(end 0.120396 0.2794)
			(stroke
				(width 0.1)
				(type default)
			)
			(layer "F.Fab")
		)
		(fp_line
			(start 0.67945 0.3048)
			(end 0.120396 0.3048)
			(stroke
				(width 0.1)
				(type default)
			)
			(layer "F.Fab")
		)
		(fp_line
			(start -0.12065 0.2794)
			(end -0.12065 0.3048)
			(stroke
				(width 0.1)
				(type default)
			)
			(layer "F.Fab")
		)
		(fp_line
			(start 0.120396 0.2794)
			(end -0.12065 0.2794)
			(stroke
				(width 0.1)
				(type default)
			)
			(layer "F.Fab")
		)
		(fp_line
			(start -0.12065 -0.2794)
			(end 0.12065 -0.2794)
			(stroke
				(width 0.1)
				(type default)
			)
			(layer "F.Fab")
		)
		(fp_line
			(start 0.12065 -0.2794)
			(end 0.12065 -0.3048)
			(stroke
				(width 0.1)
				(type default)
			)
			(layer "F.Fab")
		)
		(fp_line
			(start 0.12065 -0.3048)
			(end 0.67945 -0.3048)
			(stroke
				(width 0.1)
				(type default)
			)
			(layer "F.Fab")
		)
		(fp_line
			(start 0.67945 -0.3048)
			(end 0.67945 0.3048)
			(stroke
				(width 0.1)
				(type default)
			)
			(layer "F.Fab")
		)
		(fp_line
			(start -0.67945 -0.305054)
			(end -0.12065 -0.305054)
			(stroke
				(width 0.1)
				(type default)
			)
			(layer "F.Fab")
		)
		(fp_line
			(start -0.12065 -0.305054)
			(end -0.12065 -0.2794)
			(stroke
				(width 0.1)
				(type default)
			)
			(layer "F.Fab")
		)
		(pad "1" smd circle
			(at -0.40005 0 270)
			(size 0 0)
			(layers "F.Cu" "F.Mask" "F.Paste")
			(net "P3V3_AUX")
		)
		(pad "2" smd circle
			(at 0.40005 0 270)
			(size 0 0)
			(layers "F.Cu" "F.Mask" "F.Paste")
			(net "FM_P2E_SWB")
		)
	)
	(footprint ""
		(layer "F.Cu")
		(at 76.835 -64.008 90)
		(property "Reference" "R8095"
			(at 0 0 90)
			(layer "F.SilkS")
			(hide yes)
			(effects
				(font
					(size 1.27 1.27)
				)
			)
		)
		(property "Value" ""
			(at 0 0 90)
			(layer "F.Fab")
			(effects
				(font
					(size 1.27 1.27)
				)
			)
		)
		(duplicate_pad_numbers_are_jumpers no)
		(fp_line
			(start 0.7874 -0.4064)
			(end 0.7874 0.4064)
			(stroke
				(width 0.1524)
				(type default)
			)
			(layer "F.SilkS")
		)
		(fp_line
			(start -0.7874 -0.4064)
			(end 0.7874 -0.4064)
			(stroke
				(width 0.1524)
				(type default)
			)
			(layer "F.SilkS")
		)
		(fp_line
			(start 0.7874 0.4064)
			(end -0.7874 0.4064)
			(stroke
				(width 0.1524)
				(type default)
			)
			(layer "F.SilkS")
		)
		(fp_line
			(start -0.7874 0.4064)
			(end -0.7874 -0.4064)
			(stroke
				(width 0.1524)
				(type default)
			)
			(layer "F.SilkS")
		)
		(fp_line
			(start -0.12065 -0.305054)
			(end -0.12065 -0.2794)
			(stroke
				(width 0.1)
				(type default)
			)
			(layer "F.Fab")
		)
		(fp_line
			(start -0.67945 -0.305054)
			(end -0.12065 -0.305054)
			(stroke
				(width 0.1)
				(type default)
			)
			(layer "F.Fab")
		)
		(fp_line
			(start 0.67945 -0.3048)
			(end 0.67945 0.3048)
			(stroke
				(width 0.1)
				(type default)
			)
			(layer "F.Fab")
		)
		(fp_line
			(start 0.12065 -0.3048)
			(end 0.67945 -0.3048)
			(stroke
				(width 0.1)
				(type default)
			)
			(layer "F.Fab")
		)
		(fp_line
			(start 0.12065 -0.2794)
			(end 0.12065 -0.3048)
			(stroke
				(width 0.1)
				(type default)
			)
			(layer "F.Fab")
		)
		(fp_line
			(start -0.12065 -0.2794)
			(end 0.12065 -0.2794)
			(stroke
				(width 0.1)
				(type default)
			)
			(layer "F.Fab")
		)
		(fp_line
			(start 0.120396 0.2794)
			(end -0.12065 0.2794)
			(stroke
				(width 0.1)
				(type default)
			)
			(layer "F.Fab")
		)
		(fp_line
			(start -0.12065 0.2794)
			(end -0.12065 0.3048)
			(stroke
				(width 0.1)
				(type default)
			)
			(layer "F.Fab")
		)
		(fp_line
			(start 0.67945 0.3048)
			(end 0.120396 0.3048)
			(stroke
				(width 0.1)
				(type default)
			)
			(layer "F.Fab")
		)
		(fp_line
			(start 0.120396 0.3048)
			(end 0.120396 0.2794)
			(stroke
				(width 0.1)
				(type default)
			)
			(layer "F.Fab")
		)
		(fp_line
			(start -0.12065 0.3048)
			(end -0.67945 0.3048)
			(stroke
				(width 0.1)
				(type default)
			)
			(layer "F.Fab")
		)
		(fp_line
			(start -0.67945 0.3048)
			(end -0.67945 -0.305054)
			(stroke
				(width 0.1)
				(type default)
			)
			(layer "F.Fab")
		)
		(pad "1" smd circle
			(at -0.40005 0 90)
			(size 0 0)
			(layers "F.Cu" "F.Mask" "F.Paste")
			(net "P3V3_OCP_V3_2_R")
		)
		(pad "2" smd circle
			(at 0.40005 0 90)
			(size 0 0)
			(layers "F.Cu" "F.Mask" "F.Paste")
			(net "OCP_V3_2_P3V3_R1_PWRGD")
		)
	)
	(footprint ""
		(layer "F.Cu")
		(at 58.67273 -17.623536 90)
		(property "Reference" "C709"
			(at 0 0 90)
			(layer "F.SilkS")
			(hide yes)
			(effects
				(font
					(size 1.27 1.27)
				)
			)
		)
		(property "Value" ""
			(at 0 0 90)
			(layer "F.Fab")
			(effects
				(font
					(size 1.27 1.27)
				)
			)
		)
		(duplicate_pad_numbers_are_jumpers no)
		(fp_line
			(start 0.299974 -0.150114)
			(end 0.299974 0.150114)
			(stroke
				(width 0.1)
				(type default)
			)
			(layer "F.Fab")
		)
		(fp_line
			(start -0.299974 -0.150114)
			(end 0.299974 -0.150114)
			(stroke
				(width 0.1)
				(type default)
			)
			(layer "F.Fab")
		)
		(fp_line
			(start 0.299974 0.150114)
			(end -0.299974 0.150114)
			(stroke
				(width 0.1)
				(type default)
			)
			(layer "F.Fab")
		)
		(fp_line
			(start -0.299974 0.150114)
			(end -0.299974 -0.150114)
			(stroke
				(width 0.1)
				(type default)
			)
			(layer "F.Fab")
		)
		(pad "1" smd rect
			(at -0.2667 0 90)
			(size 0.3048 0.381)
			(layers "F.Cu" "F.Mask" "F.Paste")
			(net "P5E_CPU1_G1_TX_C_DP<0>")
		)
		(pad "2" smd rect
			(at 0.2667 0 90)
			(size 0.3048 0.381)
			(layers "F.Cu" "F.Mask" "F.Paste")
			(net "P5E_CPU1_G1_TX_DP<0>")
		)
	)
	(footprint ""
		(layer "F.Cu")
		(at 111.581946 -54.882034 90)
		(property "Reference" "R6309"
			(at 0 0 90)
			(layer "F.SilkS")
			(hide yes)
			(effects
				(font
					(size 1.27 1.27)
				)
			)
		)
		(property "Value" ""
			(at 0 0 90)
			(layer "F.Fab")
			(effects
				(font
					(size 1.27 1.27)
				)
			)
		)
		(duplicate_pad_numbers_are_jumpers no)
		(fp_line
			(start 0.7874 -0.4064)
			(end 0.7874 0.4064)
			(stroke
				(width 0.1524)
				(type default)
			)
			(layer "F.SilkS")
		)
		(fp_line
			(start -0.7874 -0.4064)
			(end 0.7874 -0.4064)
			(stroke
				(width 0.1524)
				(type default)
			)
			(layer "F.SilkS")
		)
		(fp_line
			(start 0.7874 0.4064)
			(end -0.7874 0.4064)
			(stroke
				(width 0.1524)
				(type default)
			)
			(layer "F.SilkS")
		)
		(fp_line
			(start -0.7874 0.4064)
			(end -0.7874 -0.4064)
			(stroke
				(width 0.1524)
				(type default)
			)
			(layer "F.SilkS")
		)
		(fp_line
			(start -0.12065 -0.305054)
			(end -0.12065 -0.2794)
			(stroke
				(width 0.1)
				(type default)
			)
			(layer "F.Fab")
		)
		(fp_line
			(start -0.67945 -0.305054)
			(end -0.12065 -0.305054)
			(stroke
				(width 0.1)
				(type default)
			)
			(layer "F.Fab")
		)
		(fp_line
			(start 0.67945 -0.3048)
			(end 0.67945 0.3048)
			(stroke
				(width 0.1)
				(type default)
			)
			(layer "F.Fab")
		)
		(fp_line
			(start 0.12065 -0.3048)
			(end 0.67945 -0.3048)
			(stroke
				(width 0.1)
				(type default)
			)
			(layer "F.Fab")
		)
		(fp_line
			(start 0.12065 -0.2794)
			(end 0.12065 -0.3048)
			(stroke
				(width 0.1)
				(type default)
			)
			(layer "F.Fab")
		)
		(fp_line
			(start -0.12065 -0.2794)
			(end 0.12065 -0.2794)
			(stroke
				(width 0.1)
				(type default)
			)
			(layer "F.Fab")
		)
		(fp_line
			(start 0.120396 0.2794)
			(end -0.12065 0.2794)
			(stroke
				(width 0.1)
				(type default)
			)
			(layer "F.Fab")
		)
		(fp_line
			(start -0.12065 0.2794)
			(end -0.12065 0.3048)
			(stroke
				(width 0.1)
				(type default)
			)
			(layer "F.Fab")
		)
		(fp_line
			(start 0.67945 0.3048)
			(end 0.120396 0.3048)
			(stroke
				(width 0.1)
				(type default)
			)
			(layer "F.Fab")
		)
		(fp_line
			(start 0.120396 0.3048)
			(end 0.120396 0.2794)
			(stroke
				(width 0.1)
				(type default)
			)
			(layer "F.Fab")
		)
		(fp_line
			(start -0.12065 0.3048)
			(end -0.67945 0.3048)
			(stroke
				(width 0.1)
				(type default)
			)
			(layer "F.Fab")
		)
		(fp_line
			(start -0.67945 0.3048)
			(end -0.67945 -0.305054)
			(stroke
				(width 0.1)
				(type default)
			)
			(layer "F.Fab")
		)
		(pad "1" smd circle
			(at -0.40005 0 90)
			(size 0 0)
			(layers "F.Cu" "F.Mask" "F.Paste")
			(net "USB_HUB2_MRP_CFG_NON_REM")
		)
		(pad "2" smd circle
			(at 0.40005 0 90)
			(size 0 0)
			(layers "F.Cu" "F.Mask" "F.Paste")
			(net "GND")
		)
	)
	(footprint ""
		(layer "F.Cu")
		(at 456.132184 -62.074298 90)
		(property "Reference" "PL8066"
			(at -4.96824 -7.257288 90)
			(unlocked yes)
			(layer "F.SilkS")
			(effects
				(font
					(size 0.7874 0.5842)
					(thickness 0.1524)
				)
				(justify left)
			)
		)
		(property "Value" ""
			(at 0 0 90)
			(layer "F.Fab")
			(effects
				(font
					(size 1.27 1.27)
				)
			)
		)
		(duplicate_pad_numbers_are_jumpers no)
		(fp_line
			(start 7.1501 -6.450076)
			(end -7.1501 -6.450076)
			(stroke
				(width 0.1524)
				(type default)
			)
			(layer "F.SilkS")
		)
		(fp_line
			(start -7.1501 -6.450076)
			(end -7.1501 -2.6416)
			(stroke
				(width 0.1524)
				(type default)
			)
			(layer "F.SilkS")
		)
		(fp_line
			(start 7.1501 -2.6416)
			(end 7.1501 -6.450076)
			(stroke
				(width 0.1524)
				(type default)
			)
			(layer "F.SilkS")
		)
		(fp_line
			(start 7.1501 2.6416)
			(end 7.1501 6.450076)
			(stroke
				(width 0.1524)
				(type default)
			)
			(layer "F.SilkS")
		)
		(fp_line
			(start 7.1501 6.450076)
			(end -7.1501 6.450076)
			(stroke
				(width 0.1524)
				(type default)
			)
			(layer "F.SilkS")
		)
		(fp_line
			(start -7.1501 6.450076)
			(end -7.1501 2.6416)
			(stroke
				(width 0.1524)
				(type default)
			)
			(layer "F.SilkS")
		)
		(fp_line
			(start 7.1501 -6.450076)
			(end -7.1501 -6.450076)
			(stroke
				(width 0.1)
				(type default)
			)
			(layer "F.Fab")
		)
		(fp_line
			(start -7.1501 -6.450076)
			(end -7.1501 6.450076)
			(stroke
				(width 0.1)
				(type default)
			)
			(layer "F.Fab")
		)
		(fp_line
			(start 7.1501 6.450076)
			(end 7.1501 -6.450076)
			(stroke
				(width 0.1)
				(type default)
			)
			(layer "F.Fab")
		)
		(fp_line
			(start -7.1501 6.450076)
			(end 7.1501 6.450076)
			(stroke
				(width 0.1)
				(type default)
			)
			(layer "F.Fab")
		)
		(pad "1" smd rect
			(at -5.625084 0 90)
			(size 3.2512 5.0038)
			(layers "F.Cu" "F.Mask" "F.Paste")
			(net "SW_P3V3_AUX_SW")
		)
		(pad "2" smd rect
			(at 5.625084 0 90)
			(size 3.2512 5.0038)
			(layers "F.Cu" "F.Mask" "F.Paste")
			(net "P3V3_AUX")
		)
	)
	(footprint ""
		(layer "F.Cu")
		(at 154.530044 -375.49963 -90)
		(property "Reference" "C759"
			(at 0 0 270)
			(layer "F.SilkS")
			(hide yes)
			(effects
				(font
					(size 1.27 1.27)
				)
			)
		)
		(property "Value" ""
			(at 0 0 270)
			(layer "F.Fab")
			(effects
				(font
					(size 1.27 1.27)
				)
			)
		)
		(duplicate_pad_numbers_are_jumpers no)
		(fp_line
			(start -0.299974 0.150114)
			(end -0.299974 -0.150114)
			(stroke
				(width 0.1)
				(type default)
			)
			(layer "F.Fab")
		)
		(fp_line
			(start 0.299974 0.150114)
			(end -0.299974 0.150114)
			(stroke
				(width 0.1)
				(type default)
			)
			(layer "F.Fab")
		)
		(fp_line
			(start -0.299974 -0.150114)
			(end 0.299974 -0.150114)
			(stroke
				(width 0.1)
				(type default)
			)
			(layer "F.Fab")
		)
		(fp_line
			(start 0.299974 -0.150114)
			(end 0.299974 0.150114)
			(stroke
				(width 0.1)
				(type default)
			)
			(layer "F.Fab")
		)
		(pad "1" smd rect
			(at -0.2667 0 270)
			(size 0.3048 0.381)
			(layers "F.Cu" "F.Mask" "F.Paste")
			(net "P5E_CPU1_P2_TX_C_DP<7>")
		)
		(pad "2" smd rect
			(at 0.2667 0 270)
			(size 0.3048 0.381)
			(layers "F.Cu" "F.Mask" "F.Paste")
			(net "P5E_CPU1_P2_TX_DP<7>")
		)
	)
)
